(kicad_pcb
	(version 20260206)
	(generator "pcbnew")
	(generator_version "10.0")
	(general
		(thickness 1.6)
		(legacy_teardrops no)
	)
	(paper "A4")
	(title_block
		(title "04192023_DAF0TMB3IC0_F0TG_MB_C_brd_V02_OCP.brd")
		(comment 1 "Grand Teton / footprints 2572-2577 of 8354")
	)
	(layers
		(0 "F.Cu" signal "TOP")
		(4 "In1.Cu" signal "GND")
		(6 "In2.Cu" signal "IN1")
		(8 "In3.Cu" signal "GND1")
		(10 "In4.Cu" signal "IN2")
		(12 "In5.Cu" signal "GND2")
		(14 "In6.Cu" signal "IN3")
		(16 "In7.Cu" signal "GND3")
		(18 "In8.Cu" signal "VCC")
		(20 "In9.Cu" signal "VCC1")
		(22 "In10.Cu" signal "GND4")
		(24 "In11.Cu" signal "IN4")
		(26 "In12.Cu" signal "GND5")
		(28 "In13.Cu" signal "IN5")
		(30 "In14.Cu" signal "GND6")
		(32 "In15.Cu" signal "IN6")
		(34 "In16.Cu" signal "GND7")
		(2 "B.Cu" signal "BOTTOM")
		(9 "F.Adhes" user "F.Adhesive")
		(11 "B.Adhes" user "B.Adhesive")
		(13 "F.Paste" user "Package Geometry/Pastemask Top")
		(15 "B.Paste" user "Package Geometry/Pastemask Bottom")
		(5 "F.SilkS" user "Ref Des/Silkscreen Top")
		(7 "B.SilkS" user "Ref Des/Silkscreen Bottom")
		(1 "F.Mask" user "Board Geometry/Soldermask Top")
		(3 "B.Mask" user "Board Geometry/Soldermask Bottom")
		(17 "Dwgs.User" user "User.Drawings")
		(19 "Cmts.User" user "User.Comments")
		(21 "Eco1.User" user "User.Eco1")
		(23 "Eco2.User" user "User.Eco2")
		(25 "Edge.Cuts" user "Board Geometry/Outline")
		(27 "Margin" user)
		(31 "F.CrtYd" user "Package Geometry/Place Bound Top")
		(29 "B.CrtYd" user "Package Geometry/Place Bound Bottom")
		(35 "F.Fab" user "Ref Des/Assembly Top")
		(33 "B.Fab" user "Ref Des/Assembly Bottom")
	)
	(footprint ""
		(layer "F.Cu")
		(at 366.202214 -151.857964 -90)
		(property "Reference" "PC479"
			(at 0 0 270)
			(layer "F.SilkS")
			(hide yes)
			(effects
				(font
					(size 1.27 1.27)
				)
			)
		)
		(property "Value" ""
			(at 0 0 270)
			(layer "F.Fab")
			(effects
				(font
					(size 1.27 1.27)
				)
			)
		)
		(duplicate_pad_numbers_are_jumpers no)
		(fp_line
			(start -0.7874 0.4064)
			(end -0.7874 -0.4064)
			(stroke
				(width 0.1524)
				(type default)
			)
			(layer "F.SilkS")
		)
		(fp_line
			(start 0.7874 0.4064)
			(end -0.7874 0.4064)
			(stroke
				(width 0.1524)
				(type default)
			)
			(layer "F.SilkS")
		)
		(fp_line
			(start -0.7874 -0.4064)
			(end 0.7874 -0.4064)
			(stroke
				(width 0.1524)
				(type default)
			)
			(layer "F.SilkS")
		)
		(fp_line
			(start 0.7874 -0.4064)
			(end 0.7874 0.4064)
			(stroke
				(width 0.1524)
				(type default)
			)
			(layer "F.SilkS")
		)
		(fp_line
			(start -0.67945 0.3048)
			(end -0.67945 -0.305054)
			(stroke
				(width 0.1)
				(type default)
			)
			(layer "F.Fab")
		)
		(fp_line
			(start -0.12065 0.3048)
			(end -0.67945 0.3048)
			(stroke
				(width 0.1)
				(type default)
			)
			(layer "F.Fab")
		)
		(fp_line
			(start 0.120396 0.3048)
			(end 0.120396 0.2794)
			(stroke
				(width 0.1)
				(type default)
			)
			(layer "F.Fab")
		)
		(fp_line
			(start 0.67945 0.3048)
			(end 0.120396 0.3048)
			(stroke
				(width 0.1)
				(type default)
			)
			(layer "F.Fab")
		)
		(fp_line
			(start -0.12065 0.2794)
			(end -0.12065 0.3048)
			(stroke
				(width 0.1)
				(type default)
			)
			(layer "F.Fab")
		)
		(fp_line
			(start 0.120396 0.2794)
			(end -0.12065 0.2794)
			(stroke
				(width 0.1)
				(type default)
			)
			(layer "F.Fab")
		)
		(fp_line
			(start -0.12065 -0.2794)
			(end 0.12065 -0.2794)
			(stroke
				(width 0.1)
				(type default)
			)
			(layer "F.Fab")
		)
		(fp_line
			(start 0.12065 -0.2794)
			(end 0.12065 -0.3048)
			(stroke
				(width 0.1)
				(type default)
			)
			(layer "F.Fab")
		)
		(fp_line
			(start 0.12065 -0.3048)
			(end 0.67945 -0.3048)
			(stroke
				(width 0.1)
				(type default)
			)
			(layer "F.Fab")
		)
		(fp_line
			(start 0.67945 -0.3048)
			(end 0.67945 0.3048)
			(stroke
				(width 0.1)
				(type default)
			)
			(layer "F.Fab")
		)
		(fp_line
			(start -0.67945 -0.305054)
			(end -0.12065 -0.305054)
			(stroke
				(width 0.1)
				(type default)
			)
			(layer "F.Fab")
		)
		(fp_line
			(start -0.12065 -0.305054)
			(end -0.12065 -0.2794)
			(stroke
				(width 0.1)
				(type default)
			)
			(layer "F.Fab")
		)
		(pad "1" smd circle
			(at -0.40005 0 270)
			(size 0 0)
			(layers "F.Cu" "F.Mask" "F.Paste")
			(net "P12V_AUX")
		)
		(pad "2" smd circle
			(at 0.40005 0 270)
			(size 0 0)
			(layers "F.Cu" "F.Mask" "F.Paste")
			(net "GND")
		)
	)
	(footprint ""
		(layer "F.Cu")
		(at 362.984288 -415.729166 90)
		(property "Reference" "Q9000"
			(at -1.462278 1.708658 90)
			(unlocked yes)
			(layer "F.SilkS")
			(effects
				(font
					(size 0.7874 0.5842)
					(thickness 0.1524)
				)
				(justify left)
			)
		)
		(property "Value" ""
			(at 0 0 90)
			(layer "F.Fab")
			(effects
				(font
					(size 1.27 1.27)
				)
			)
		)
		(duplicate_pad_numbers_are_jumpers no)
		(fp_line
			(start 1.332738 -1.100074)
			(end 1.332738 1.100074)
			(stroke
				(width 0.1524)
				(type default)
			)
			(layer "F.SilkS")
		)
		(fp_line
			(start 0.4826 -1.100074)
			(end 1.332738 -1.100074)
			(stroke
				(width 0.1524)
				(type default)
			)
			(layer "F.SilkS")
		)
		(fp_line
			(start -0.4826 -1.100074)
			(end 0 -0.541274)
			(stroke
				(width 0.1524)
				(type default)
			)
			(layer "F.SilkS")
		)
		(fp_line
			(start -1.332738 -1.100074)
			(end -0.4826 -1.100074)
			(stroke
				(width 0.1524)
				(type default)
			)
			(layer "F.SilkS")
		)
		(fp_line
			(start 0 -0.541274)
			(end 0.4826 -1.100074)
			(stroke
				(width 0.1524)
				(type default)
			)
			(layer "F.SilkS")
		)
		(fp_line
			(start 1.332738 1.100074)
			(end -1.332738 1.100074)
			(stroke
				(width 0.1524)
				(type default)
			)
			(layer "F.SilkS")
		)
		(fp_line
			(start -1.332738 1.100074)
			(end -1.332738 -1.100074)
			(stroke
				(width 0.1524)
				(type default)
			)
			(layer "F.SilkS")
		)
		(fp_poly
			(pts
				(xy -2.2352 -0.298958) (xy -2.2352 -1.001014) (xy -1.533144 -0.649986)
			)
			(stroke
				(width 0)
				(type default)
			)
			(fill yes)
			(layer "F.SilkS")
		)
		(fp_line
			(start 0.674878 -1.100074)
			(end 0.674878 1.100074)
			(stroke
				(width 0.1)
				(type default)
			)
			(layer "F.Fab")
		)
		(fp_line
			(start -0.674878 -1.100074)
			(end 0.674878 -1.100074)
			(stroke
				(width 0.1)
				(type default)
			)
			(layer "F.Fab")
		)
		(fp_line
			(start 0.674878 1.100074)
			(end -0.674878 1.100074)
			(stroke
				(width 0.1)
				(type default)
			)
			(layer "F.Fab")
		)
		(fp_line
			(start -0.674878 1.100074)
			(end -0.674878 -1.100074)
			(stroke
				(width 0.1)
				(type default)
			)
			(layer "F.Fab")
		)
		(fp_poly
			(pts
				(xy -2.2352 -0.298958) (xy -2.2352 -1.001014) (xy -1.533144 -0.649986)
			)
			(stroke
				(width 0)
				(type default)
			)
			(fill yes)
			(layer "F.Fab")
		)
		(pad "1" smd rect
			(at -0.94996 -0.649986 180)
			(size 0.4318 0.508)
			(layers "F.Cu" "F.Mask" "F.Paste")
			(net "GND")
		)
		(pad "2" smd rect
			(at -0.94996 0 180)
			(size 0.4318 0.508)
			(layers "F.Cu" "F.Mask" "F.Paste")
			(net "PRSNT_CABLE_SWB_B1_N")
		)
		(pad "3" smd rect
			(at -0.94996 0.649986 180)
			(size 0.4318 0.508)
			(layers "F.Cu" "F.Mask" "F.Paste")
			(net "PRSNT_CABLE_SWB_B1_ISO_N")
		)
		(pad "4" smd rect
			(at 0.94996 0.649986 180)
			(size 0.4318 0.508)
			(layers "F.Cu" "F.Mask" "F.Paste")
			(net "GND")
		)
		(pad "5" smd rect
			(at 0.94996 0 180)
			(size 0.4318 0.508)
			(layers "F.Cu" "F.Mask" "F.Paste")
			(net "PRSNT_CABLE_SWB_B1")
		)
		(pad "6" smd rect
			(at 0.94996 -0.649986 180)
			(size 0.4318 0.508)
			(layers "F.Cu" "F.Mask" "F.Paste")
			(net "PRSNT_CABLE_SWB_B1")
		)
	)
	(footprint ""
		(layer "F.Cu")
		(at 421.54094 -101.270308 -90)
		(property "Reference" "PC2157"
			(at 0 0 270)
			(layer "F.SilkS")
			(hide yes)
			(effects
				(font
					(size 1.27 1.27)
				)
			)
		)
		(property "Value" ""
			(at 0 0 270)
			(layer "F.Fab")
			(effects
				(font
					(size 1.27 1.27)
				)
			)
		)
		(duplicate_pad_numbers_are_jumpers no)
		(fp_line
			(start -0.7874 0.4064)
			(end -0.7874 -0.4064)
			(stroke
				(width 0.1524)
				(type default)
			)
			(layer "F.SilkS")
		)
		(fp_line
			(start 0.7874 0.4064)
			(end -0.7874 0.4064)
			(stroke
				(width 0.1524)
				(type default)
			)
			(layer "F.SilkS")
		)
		(fp_line
			(start -0.7874 -0.4064)
			(end 0.7874 -0.4064)
			(stroke
				(width 0.1524)
				(type default)
			)
			(layer "F.SilkS")
		)
		(fp_line
			(start 0.7874 -0.4064)
			(end 0.7874 0.4064)
			(stroke
				(width 0.1524)
				(type default)
			)
			(layer "F.SilkS")
		)
		(fp_line
			(start -0.67945 0.3048)
			(end -0.67945 -0.305054)
			(stroke
				(width 0.1)
				(type default)
			)
			(layer "F.Fab")
		)
		(fp_line
			(start -0.12065 0.3048)
			(end -0.67945 0.3048)
			(stroke
				(width 0.1)
				(type default)
			)
			(layer "F.Fab")
		)
		(fp_line
			(start 0.120396 0.3048)
			(end 0.120396 0.2794)
			(stroke
				(width 0.1)
				(type default)
			)
			(layer "F.Fab")
		)
		(fp_line
			(start 0.67945 0.3048)
			(end 0.120396 0.3048)
			(stroke
				(width 0.1)
				(type default)
			)
			(layer "F.Fab")
		)
		(fp_line
			(start -0.12065 0.2794)
			(end -0.12065 0.3048)
			(stroke
				(width 0.1)
				(type default)
			)
			(layer "F.Fab")
		)
		(fp_line
			(start 0.120396 0.2794)
			(end -0.12065 0.2794)
			(stroke
				(width 0.1)
				(type default)
			)
			(layer "F.Fab")
		)
		(fp_line
			(start -0.12065 -0.2794)
			(end 0.12065 -0.2794)
			(stroke
				(width 0.1)
				(type default)
			)
			(layer "F.Fab")
		)
		(fp_line
			(start 0.12065 -0.2794)
			(end 0.12065 -0.3048)
			(stroke
				(width 0.1)
				(type default)
			)
			(layer "F.Fab")
		)
		(fp_line
			(start 0.12065 -0.3048)
			(end 0.67945 -0.3048)
			(stroke
				(width 0.1)
				(type default)
			)
			(layer "F.Fab")
		)
		(fp_line
			(start 0.67945 -0.3048)
			(end 0.67945 0.3048)
			(stroke
				(width 0.1)
				(type default)
			)
			(layer "F.Fab")
		)
		(fp_line
			(start -0.67945 -0.305054)
			(end -0.12065 -0.305054)
			(stroke
				(width 0.1)
				(type default)
			)
			(layer "F.Fab")
		)
		(fp_line
			(start -0.12065 -0.305054)
			(end -0.12065 -0.2794)
			(stroke
				(width 0.1)
				(type default)
			)
			(layer "F.Fab")
		)
		(pad "1" smd circle
			(at -0.40005 0 270)
			(size 0 0)
			(layers "F.Cu" "F.Mask" "F.Paste")
			(net "P3V3_OCP_MODE_1")
		)
		(pad "2" smd circle
			(at 0.40005 0 270)
			(size 0 0)
			(layers "F.Cu" "F.Mask" "F.Paste")
			(net "GND")
		)
	)
	(footprint ""
		(layer "F.Cu")
		(at 35.395662 -429.790098 90)
		(property "Reference" "R3287"
			(at 0 0 90)
			(layer "F.SilkS")
			(hide yes)
			(effects
				(font
					(size 1.27 1.27)
				)
			)
		)
		(property "Value" ""
			(at 0 0 90)
			(layer "F.Fab")
			(effects
				(font
					(size 1.27 1.27)
				)
			)
		)
		(duplicate_pad_numbers_are_jumpers no)
		(fp_line
			(start 0.7874 -0.4064)
			(end 0.7874 0.4064)
			(stroke
				(width 0.1524)
				(type default)
			)
			(layer "F.SilkS")
		)
		(fp_line
			(start -0.7874 -0.4064)
			(end 0.7874 -0.4064)
			(stroke
				(width 0.1524)
				(type default)
			)
			(layer "F.SilkS")
		)
		(fp_line
			(start 0.7874 0.4064)
			(end -0.7874 0.4064)
			(stroke
				(width 0.1524)
				(type default)
			)
			(layer "F.SilkS")
		)
		(fp_line
			(start -0.7874 0.4064)
			(end -0.7874 -0.4064)
			(stroke
				(width 0.1524)
				(type default)
			)
			(layer "F.SilkS")
		)
		(fp_line
			(start -0.12065 -0.305054)
			(end -0.12065 -0.2794)
			(stroke
				(width 0.1)
				(type default)
			)
			(layer "F.Fab")
		)
		(fp_line
			(start -0.67945 -0.305054)
			(end -0.12065 -0.305054)
			(stroke
				(width 0.1)
				(type default)
			)
			(layer "F.Fab")
		)
		(fp_line
			(start 0.67945 -0.3048)
			(end 0.67945 0.3048)
			(stroke
				(width 0.1)
				(type default)
			)
			(layer "F.Fab")
		)
		(fp_line
			(start 0.12065 -0.3048)
			(end 0.67945 -0.3048)
			(stroke
				(width 0.1)
				(type default)
			)
			(layer "F.Fab")
		)
		(fp_line
			(start 0.12065 -0.2794)
			(end 0.12065 -0.3048)
			(stroke
				(width 0.1)
				(type default)
			)
			(layer "F.Fab")
		)
		(fp_line
			(start -0.12065 -0.2794)
			(end 0.12065 -0.2794)
			(stroke
				(width 0.1)
				(type default)
			)
			(layer "F.Fab")
		)
		(fp_line
			(start 0.120396 0.2794)
			(end -0.12065 0.2794)
			(stroke
				(width 0.1)
				(type default)
			)
			(layer "F.Fab")
		)
		(fp_line
			(start -0.12065 0.2794)
			(end -0.12065 0.3048)
			(stroke
				(width 0.1)
				(type default)
			)
			(layer "F.Fab")
		)
		(fp_line
			(start 0.67945 0.3048)
			(end 0.120396 0.3048)
			(stroke
				(width 0.1)
				(type default)
			)
			(layer "F.Fab")
		)
		(fp_line
			(start 0.120396 0.3048)
			(end 0.120396 0.2794)
			(stroke
				(width 0.1)
				(type default)
			)
			(layer "F.Fab")
		)
		(fp_line
			(start -0.12065 0.3048)
			(end -0.67945 0.3048)
			(stroke
				(width 0.1)
				(type default)
			)
			(layer "F.Fab")
		)
		(fp_line
			(start -0.67945 0.3048)
			(end -0.67945 -0.305054)
			(stroke
				(width 0.1)
				(type default)
			)
			(layer "F.Fab")
		)
		(pad "1" smd circle
			(at -0.40005 0 90)
			(size 0 0)
			(layers "F.Cu" "F.Mask" "F.Paste")
			(net "FM_P2E_SWB")
		)
		(pad "2" smd circle
			(at 0.40005 0 90)
			(size 0 0)
			(layers "F.Cu" "F.Mask" "F.Paste")
			(net "GND")
		)
	)
	(footprint ""
		(layer "F.Cu")
		(at 154.633676 -48.961294 -90)
		(property "Reference" "R3590"
			(at 0 0 270)
			(layer "F.SilkS")
			(hide yes)
			(effects
				(font
					(size 1.27 1.27)
				)
			)
		)
		(property "Value" ""
			(at 0 0 270)
			(layer "F.Fab")
			(effects
				(font
					(size 1.27 1.27)
				)
			)
		)
		(duplicate_pad_numbers_are_jumpers no)
		(fp_line
			(start -0.7874 0.4064)
			(end -0.7874 -0.4064)
			(stroke
				(width 0.1524)
				(type default)
			)
			(layer "F.SilkS")
		)
		(fp_line
			(start 0.7874 0.4064)
			(end -0.7874 0.4064)
			(stroke
				(width 0.1524)
				(type default)
			)
			(layer "F.SilkS")
		)
		(fp_line
			(start -0.7874 -0.4064)
			(end 0.7874 -0.4064)
			(stroke
				(width 0.1524)
				(type default)
			)
			(layer "F.SilkS")
		)
		(fp_line
			(start 0.7874 -0.4064)
			(end 0.7874 0.4064)
			(stroke
				(width 0.1524)
				(type default)
			)
			(layer "F.SilkS")
		)
		(fp_line
			(start -0.67945 0.3048)
			(end -0.67945 -0.305054)
			(stroke
				(width 0.1)
				(type default)
			)
			(layer "F.Fab")
		)
		(fp_line
			(start -0.12065 0.3048)
			(end -0.67945 0.3048)
			(stroke
				(width 0.1)
				(type default)
			)
			(layer "F.Fab")
		)
		(fp_line
			(start 0.120396 0.3048)
			(end 0.120396 0.2794)
			(stroke
				(width 0.1)
				(type default)
			)
			(layer "F.Fab")
		)
		(fp_line
			(start 0.67945 0.3048)
			(end 0.120396 0.3048)
			(stroke
				(width 0.1)
				(type default)
			)
			(layer "F.Fab")
		)
		(fp_line
			(start -0.12065 0.2794)
			(end -0.12065 0.3048)
			(stroke
				(width 0.1)
				(type default)
			)
			(layer "F.Fab")
		)
		(fp_line
			(start 0.120396 0.2794)
			(end -0.12065 0.2794)
			(stroke
				(width 0.1)
				(type default)
			)
			(layer "F.Fab")
		)
		(fp_line
			(start -0.12065 -0.2794)
			(end 0.12065 -0.2794)
			(stroke
				(width 0.1)
				(type default)
			)
			(layer "F.Fab")
		)
		(fp_line
			(start 0.12065 -0.2794)
			(end 0.12065 -0.3048)
			(stroke
				(width 0.1)
				(type default)
			)
			(layer "F.Fab")
		)
		(fp_line
			(start 0.12065 -0.3048)
			(end 0.67945 -0.3048)
			(stroke
				(width 0.1)
				(type default)
			)
			(layer "F.Fab")
		)
		(fp_line
			(start 0.67945 -0.3048)
			(end 0.67945 0.3048)
			(stroke
				(width 0.1)
				(type default)
			)
			(layer "F.Fab")
		)
		(fp_line
			(start -0.67945 -0.305054)
			(end -0.12065 -0.305054)
			(stroke
				(width 0.1)
				(type default)
			)
			(layer "F.Fab")
		)
		(fp_line
			(start -0.12065 -0.305054)
			(end -0.12065 -0.2794)
			(stroke
				(width 0.1)
				(type default)
			)
			(layer "F.Fab")
		)
		(pad "1" smd circle
			(at -0.40005 0 270)
			(size 0 0)
			(layers "F.Cu" "F.Mask" "F.Paste")
			(net "SMB_INA230_3V3AUX_SCL")
		)
		(pad "2" smd circle
			(at 0.40005 0 270)
			(size 0 0)
			(layers "F.Cu" "F.Mask" "F.Paste")
			(net "SMB_INA230_3_3V3AUX_SCL_R")
		)
	)
	(footprint ""
		(layer "F.Cu")
		(at 18.076672 -396.076678 180)
		(property "Reference" "PC6638_2"
			(at 0 0 180)
			(layer "F.SilkS")
			(hide yes)
			(effects
				(font
					(size 1.27 1.27)
				)
			)
		)
		(property "Value" ""
			(at 0 0 180)
			(layer "F.Fab")
			(effects
				(font
					(size 1.27 1.27)
				)
			)
		)
		(duplicate_pad_numbers_are_jumpers no)
		(fp_line
			(start 1.524 0.762)
			(end -1.524 0.762)
			(stroke
				(width 0.1524)
				(type default)
			)
			(layer "F.SilkS")
		)
		(fp_line
			(start 1.524 -0.762)
			(end 1.524 0.762)
			(stroke
				(width 0.1524)
				(type default)
			)
			(layer "F.SilkS")
		)
		(fp_line
			(start -1.524 0.762)
			(end -1.524 -0.762)
			(stroke
				(width 0.1524)
				(type default)
			)
			(layer "F.SilkS")
		)
		(fp_line
			(start -1.524 -0.762)
			(end 1.524 -0.762)
			(stroke
				(width 0.1524)
				(type default)
			)
			(layer "F.SilkS")
		)
		(fp_line
			(start 1.1049 0.724916)
			(end 1.1049 -0.724916)
			(stroke
				(width 0.1)
				(type default)
			)
			(layer "F.Fab")
		)
		(fp_line
			(start 1.1049 -0.724916)
			(end -1.1049 -0.724916)
			(stroke
				(width 0.1)
				(type default)
			)
			(layer "F.Fab")
		)
		(fp_line
			(start -1.1049 0.724916)
			(end 1.1049 0.724916)
			(stroke
				(width 0.1)
				(type default)
			)
			(layer "F.Fab")
		)
		(fp_line
			(start -1.1049 -0.724916)
			(end -1.1049 0.724916)
			(stroke
				(width 0.1)
				(type default)
			)
			(layer "F.Fab")
		)
		(pad "1" smd rect
			(at -0.889 0)
			(size 1.016 1.27)
			(layers "F.Cu" "F.Mask" "F.Paste")
			(net "SW_P12V_AUX_P0V9_RETIMER_CPU1_FLT")
		)
		(pad "2" smd rect
			(at 0.889 0)
			(size 1.016 1.27)
			(layers "F.Cu" "F.Mask" "F.Paste")
			(net "GND")
		)
	)
)
